# T6G (Grand Teton) — schematic netlist excerpt (pin names and nets, part order shuffled) for the footprints in the layout excerpt that follows; sources: Cadence DE-HDL packaged netlist, KiCad conversion of 04192023_DAF0TMB3IC0_F0TG_MB_C_brd_V02_OCP.brd

C7007  Q_CAP  47UF 4V 20% X6S  pkg C0805  page 345 : A = P0V9_CPU1_RT_2D ; B = GND
R3203  Q_RES  33.2 1% CHIP  pkg 0402LF  page 138 : A = OCP_V3_2_AUX_PWR_EN ; B = OCP_V3_2_AUX_PWR_EN_R1
R9021  Q_RES  1K 1% EMPTY  pkg 0402LF  page 268 : A = P12V_AUX ; B = U206_VS

(kicad_pcb
	(version 20260206)
	(generator "pcbnew")
	(generator_version "10.0")
	(general
		(thickness 1.6)
		(legacy_teardrops no)
	)
	(paper "A4")
	(title_block
		(title "04192023_DAF0TMB3IC0_F0TG_MB_C_brd_V02_OCP.brd")
		(comment 1 "Grand Teton / footprints 1346-1348 of 8354")
	)
	(layers
		(0 "F.Cu" signal "TOP")
		(4 "In1.Cu" signal "GND")
		(6 "In2.Cu" signal "IN1")
		(8 "In3.Cu" signal "GND1")
		(10 "In4.Cu" signal "IN2")
		(12 "In5.Cu" signal "GND2")
		(14 "In6.Cu" signal "IN3")
		(16 "In7.Cu" signal "GND3")
		(18 "In8.Cu" signal "VCC")
		(20 "In9.Cu" signal "VCC1")
		(22 "In10.Cu" signal "GND4")
		(24 "In11.Cu" signal "IN4")
		(26 "In12.Cu" signal "GND5")
		(28 "In13.Cu" signal "IN5")
		(30 "In14.Cu" signal "GND6")
		(32 "In15.Cu" signal "IN6")
		(34 "In16.Cu" signal "GND7")
		(2 "B.Cu" signal "BOTTOM")
		(9 "F.Adhes" user "F.Adhesive")
		(11 "B.Adhes" user "B.Adhesive")
		(13 "F.Paste" user "Package Geometry/Pastemask Top")
		(15 "B.Paste" user "Package Geometry/Pastemask Bottom")
		(5 "F.SilkS" user "Ref Des/Silkscreen Top")
		(7 "B.SilkS" user "Ref Des/Silkscreen Bottom")
		(1 "F.Mask" user "Board Geometry/Soldermask Top")
		(3 "B.Mask" user "Board Geometry/Soldermask Bottom")
		(17 "Dwgs.User" user "User.Drawings")
		(19 "Cmts.User" user "User.Comments")
		(21 "Eco1.User" user "User.Eco1")
		(23 "Eco2.User" user "User.Eco2")
		(25 "Edge.Cuts" user "Board Geometry/Outline")
		(27 "Margin" user)
		(31 "F.CrtYd" user "Package Geometry/Place Bound Top")
		(29 "B.CrtYd" user "Package Geometry/Place Bound Bottom")
		(35 "F.Fab" user "Ref Des/Assembly Top")
		(33 "B.Fab" user "Ref Des/Assembly Bottom")
	)
	(footprint ""
		(layer "F.Cu")
		(at 49.778666 -25.309068 90)
		(property "Reference" "R3203"
			(at 0 0 90)
			(layer "F.SilkS")
			(hide yes)
			(effects
				(font
					(size 1.27 1.27)
				)
			)
		)
		(property "Value" ""
			(at 0 0 90)
			(layer "F.Fab")
			(effects
				(font
					(size 1.27 1.27)
				)
			)
		)
		(duplicate_pad_numbers_are_jumpers no)
		(fp_line
			(start 0.7874 -0.4064)
			(end 0.7874 0.4064)
			(stroke
				(width 0.1524)
				(type default)
			)
			(layer "F.SilkS")
		)
		(fp_line
			(start -0.7874 -0.4064)
			(end 0.7874 -0.4064)
			(stroke
				(width 0.1524)
				(type default)
			)
			(layer "F.SilkS")
		)
		(fp_line
			(start 0.7874 0.4064)
			(end -0.7874 0.4064)
			(stroke
				(width 0.1524)
				(type default)
			)
			(layer "F.SilkS")
		)
		(fp_line
			(start -0.7874 0.4064)
			(end -0.7874 -0.4064)
			(stroke
				(width 0.1524)
				(type default)
			)
			(layer "F.SilkS")
		)
		(fp_line
			(start -0.12065 -0.305054)
			(end -0.12065 -0.2794)
			(stroke
				(width 0.1)
				(type default)
			)
			(layer "F.Fab")
		)
		(fp_line
			(start -0.67945 -0.305054)
			(end -0.12065 -0.305054)
			(stroke
				(width 0.1)
				(type default)
			)
			(layer "F.Fab")
		)
		(fp_line
			(start 0.67945 -0.3048)
			(end 0.67945 0.3048)
			(stroke
				(width 0.1)
				(type default)
			)
			(layer "F.Fab")
		)
		(fp_line
			(start 0.12065 -0.3048)
			(end 0.67945 -0.3048)
			(stroke
				(width 0.1)
				(type default)
			)
			(layer "F.Fab")
		)
		(fp_line
			(start 0.12065 -0.2794)
			(end 0.12065 -0.3048)
			(stroke
				(width 0.1)
				(type default)
			)
			(layer "F.Fab")
		)
		(fp_line
			(start -0.12065 -0.2794)
			(end 0.12065 -0.2794)
			(stroke
				(width 0.1)
				(type default)
			)
			(layer "F.Fab")
		)
		(fp_line
			(start 0.120396 0.2794)
			(end -0.12065 0.2794)
			(stroke
				(width 0.1)
				(type default)
			)
			(layer "F.Fab")
		)
		(fp_line
			(start -0.12065 0.2794)
			(end -0.12065 0.3048)
			(stroke
				(width 0.1)
				(type default)
			)
			(layer "F.Fab")
		)
		(fp_line
			(start 0.67945 0.3048)
			(end 0.120396 0.3048)
			(stroke
				(width 0.1)
				(type default)
			)
			(layer "F.Fab")
		)
		(fp_line
			(start 0.120396 0.3048)
			(end 0.120396 0.2794)
			(stroke
				(width 0.1)
				(type default)
			)
			(layer "F.Fab")
		)
		(fp_line
			(start -0.12065 0.3048)
			(end -0.67945 0.3048)
			(stroke
				(width 0.1)
				(type default)
			)
			(layer "F.Fab")
		)
		(fp_line
			(start -0.67945 0.3048)
			(end -0.67945 -0.305054)
			(stroke
				(width 0.1)
				(type default)
			)
			(layer "F.Fab")
		)
		(pad "1" smd circle
			(at -0.40005 0 90)
			(size 0 0)
			(layers "F.Cu" "F.Mask" "F.Paste")
			(net "OCP_V3_2_AUX_PWR_EN")
		)
		(pad "2" smd circle
			(at 0.40005 0 90)
			(size 0 0)
			(layers "F.Cu" "F.Mask" "F.Paste")
			(net "OCP_V3_2_AUX_PWR_EN_R1")
		)
	)
	(footprint ""
		(layer "F.Cu")
		(at 148.971 -118.364 -90)
		(property "Reference" "R9021"
			(at 0 0 270)
			(layer "F.SilkS")
			(hide yes)
			(effects
				(font
					(size 1.27 1.27)
				)
			)
		)
		(property "Value" ""
			(at 0 0 270)
			(layer "F.Fab")
			(effects
				(font
					(size 1.27 1.27)
				)
			)
		)
		(duplicate_pad_numbers_are_jumpers no)
		(fp_line
			(start -0.7874 0.4064)
			(end -0.7874 -0.4064)
			(stroke
				(width 0.1524)
				(type default)
			)
			(layer "F.SilkS")
		)
		(fp_line
			(start 0.7874 0.4064)
			(end -0.7874 0.4064)
			(stroke
				(width 0.1524)
				(type default)
			)
			(layer "F.SilkS")
		)
		(fp_line
			(start -0.7874 -0.4064)
			(end 0.7874 -0.4064)
			(stroke
				(width 0.1524)
				(type default)
			)
			(layer "F.SilkS")
		)
		(fp_line
			(start 0.7874 -0.4064)
			(end 0.7874 0.4064)
			(stroke
				(width 0.1524)
				(type default)
			)
			(layer "F.SilkS")
		)
		(fp_line
			(start -0.67945 0.3048)
			(end -0.67945 -0.305054)
			(stroke
				(width 0.1)
				(type default)
			)
			(layer "F.Fab")
		)
		(fp_line
			(start -0.12065 0.3048)
			(end -0.67945 0.3048)
			(stroke
				(width 0.1)
				(type default)
			)
			(layer "F.Fab")
		)
		(fp_line
			(start 0.120396 0.3048)
			(end 0.120396 0.2794)
			(stroke
				(width 0.1)
				(type default)
			)
			(layer "F.Fab")
		)
		(fp_line
			(start 0.67945 0.3048)
			(end 0.120396 0.3048)
			(stroke
				(width 0.1)
				(type default)
			)
			(layer "F.Fab")
		)
		(fp_line
			(start -0.12065 0.2794)
			(end -0.12065 0.3048)
			(stroke
				(width 0.1)
				(type default)
			)
			(layer "F.Fab")
		)
		(fp_line
			(start 0.120396 0.2794)
			(end -0.12065 0.2794)
			(stroke
				(width 0.1)
				(type default)
			)
			(layer "F.Fab")
		)
		(fp_line
			(start -0.12065 -0.2794)
			(end 0.12065 -0.2794)
			(stroke
				(width 0.1)
				(type default)
			)
			(layer "F.Fab")
		)
		(fp_line
			(start 0.12065 -0.2794)
			(end 0.12065 -0.3048)
			(stroke
				(width 0.1)
				(type default)
			)
			(layer "F.Fab")
		)
		(fp_line
			(start 0.12065 -0.3048)
			(end 0.67945 -0.3048)
			(stroke
				(width 0.1)
				(type default)
			)
			(layer "F.Fab")
		)
		(fp_line
			(start 0.67945 -0.3048)
			(end 0.67945 0.3048)
			(stroke
				(width 0.1)
				(type default)
			)
			(layer "F.Fab")
		)
		(fp_line
			(start -0.67945 -0.305054)
			(end -0.12065 -0.305054)
			(stroke
				(width 0.1)
				(type default)
			)
			(layer "F.Fab")
		)
		(fp_line
			(start -0.12065 -0.305054)
			(end -0.12065 -0.2794)
			(stroke
				(width 0.1)
				(type default)
			)
			(layer "F.Fab")
		)
		(pad "1" smd circle
			(at -0.40005 0 270)
			(size 0 0)
			(layers "F.Cu" "F.Mask" "F.Paste")
			(net "P12V_AUX")
		)
		(pad "2" smd circle
			(at 0.40005 0 270)
			(size 0 0)
			(layers "F.Cu" "F.Mask" "F.Paste")
			(net "U206_VS")
		)
	)
	(footprint ""
		(layer "F.Cu")
		(at 74.357738 -401.884388 90)
		(property "Reference" "C7007"
			(at 0 0 90)
			(layer "F.SilkS")
			(hide yes)
			(effects
				(font
					(size 1.27 1.27)
				)
			)
		)
		(property "Value" ""
			(at 0 0 90)
			(layer "F.Fab")
			(effects
				(font
					(size 1.27 1.27)
				)
			)
		)
		(duplicate_pad_numbers_are_jumpers no)
		(fp_line
			(start 1.524 -0.762)
			(end 1.524 0.762)
			(stroke
				(width 0.1524)
				(type default)
			)
			(layer "F.SilkS")
		)
		(fp_line
			(start -1.524 -0.762)
			(end 1.524 -0.762)
			(stroke
				(width 0.1524)
				(type default)
			)
			(layer "F.SilkS")
		)
		(fp_line
			(start 1.524 0.762)
			(end -1.524 0.762)
			(stroke
				(width 0.1524)
				(type default)
			)
			(layer "F.SilkS")
		)
		(fp_line
			(start -1.524 0.762)
			(end -1.524 -0.762)
			(stroke
				(width 0.1524)
				(type default)
			)
			(layer "F.SilkS")
		)
		(fp_line
			(start 1.1049 -0.724916)
			(end -1.1049 -0.724916)
			(stroke
				(width 0.1)
				(type default)
			)
			(layer "F.Fab")
		)
		(fp_line
			(start -1.1049 -0.724916)
			(end -1.1049 0.724916)
			(stroke
				(width 0.1)
				(type default)
			)
			(layer "F.Fab")
		)
		(fp_line
			(start 1.1049 0.724916)
			(end 1.1049 -0.724916)
			(stroke
				(width 0.1)
				(type default)
			)
			(layer "F.Fab")
		)
		(fp_line
			(start -1.1049 0.724916)
			(end 1.1049 0.724916)
			(stroke
				(width 0.1)
				(type default)
			)
			(layer "F.Fab")
		)
		(pad "1" smd rect
			(at -0.889 0 270)
			(size 1.016 1.27)
			(layers "F.Cu" "F.Mask" "F.Paste")
			(net "P0V9_CPU1_RT_2D")
		)
		(pad "2" smd rect
			(at 0.889 0 270)
			(size 1.016 1.27)
			(layers "F.Cu" "F.Mask" "F.Paste")
			(net "GND")
		)
	)
)
